FILE_TYPE = CONNECTIVITY;
{Allegro Design Entry HDL 17.2-2016 S081 (4005846) 1/11/2022}
"PAGE_NUMBER" = 42;
0"NC";
1"GND\g";
2"GND\g";
3"GND\g";
4"GND\g";
5"GND\g";
%"UNIVERSAL_GND"
"1","(-3275,-850)","0","logical_power","I1";
;
CDS_LIB"logical_power"
HDL_POWER"GND";
"A"5;
%"SOCKET4677_AZIF0045P001C01CS"
"40","(-1825,1675)","0","pure_quanta","I10";
;
PART_NUMBER"DGA^7000023"
PART_TYPE"SMLF"
MATERIAL"IO"
VALUE"SOCKET4677_AZIF0045-P001C01CS"
$LOCATION"U2"
CDS_LIB"pure_quanta"
NEEDS_NO_SIZE"TRUE"
CDS_LMAN_SYM_OUTLINE"-1050,2150,1050,-2100"
CDS_LOCATION"U2"
$SEC"40"
CDS_SEC"40";
"VSS17"
$PN"AA19"5;
"VSS18"
$PN"AA23"5;
"VSS19"
$PN"AA25"5;
"VSS20"
$PN"AA29"5;
"VSS21"
$PN"AA31"5;
"VSS22"
$PN"AA35"5;
"VSS23"
$PN"AA37"5;
"VSS24"
$PN"AA41"5;
"VSS25"
$PN"AA43"5;
"VSS26"
$PN"AA48"5;
"VSS27"
$PN"AA50"5;
"VSS28"
$PN"AA54"5;
"VSS29"
$PN"AA56"5;
"VSS30"
$PN"AA60"5;
"VSS31"
$PN"AA62"5;
"VSS32"
$PN"AA66"5;
"VSS33"
$PN"AA68"5;
"VSS34"
$PN"AA72"5;
"VSS35"
$PN"AA74"5;
"VSS36"
$PN"AA78"5;
"VSS37"
$PN"AA80"5;
"VSS1690"
$PN"P32"4;
"VSS1696"
$PN"N76"4;
"VSS1697"
$PN"P51"4;
"VSS1698"
$PN"N78"4;
"VSS1699"
$PN"P57"4;
"VSS1700"
$PN"N80"4;
"VSS1701"
$PN"N82"4;
"VSS1702"
$PN"N84"4;
"VSS1703"
$PN"N88"4;
"VSS1704"
$PN"P71"4;
"VSS1705"
$PN"P12"4;
"VSS1706"
$PN"P16"4;
"VSS1707"
$PN"P20"4;
"VSS1708"
$PN"P22"4;
"VSS1709"
$PN"P26"4;
"VSS1710"
$PN"P28"4;
"VSS1711"
$PN"R1"4;
"VSS1712"
$PN"P34"4;
"VSS1713"
$PN"P38"4;
"VSS1714"
$PN"R19"4;
"VSS1715"
$PN"R23"4;
"VSS1716"
$PN"P4"4;
"VSS1717"
$PN"P40"4;
"VSS1718"
$PN"P44"4;
"VSS1719"
$PN"P47"4;
"VSS1720"
$PN"P53"4;
"VSS1721"
$PN"P59"4;
"VSS1722"
$PN"P63"4;
"VSS1723"
$PN"R48"4;
"VSS1724"
$PN"P65"4;
"VSS1725"
$PN"P69"4;
"VSS1726"
$PN"P75"4;
"VSS1727"
$PN"P77"4;
"VSS1728"
$PN"R60"4;
"VSS1729"
$PN"P8"4;
"VSS1730"
$PN"R66"4;
"VSS1731"
$PN"P87"4;
"VSS1732"
$PN"P91"4;
"VSS1733"
$PN"R13"4;
"VSS1734"
$PN"R17"4;
"VSS1735"
$PN"R25"4;
"VSS1736"
$PN"R29"4;
"VSS1737"
$PN"R31"4;
"VSS1738"
$PN"R35"4;
"VSS1739"
$PN"T12"4;
"VSS1740"
$PN"T16"4;
"VSS1741"
$PN"T18"4;
"VSS1742"
$PN"R37"4;
"VSS1743"
$PN"R41"4;
"VSS1744"
$PN"R43"4;
"VSS1745"
$PN"R5"4;
"VSS1746"
$PN"T36"4;
"VSS1747"
$PN"R50"4;
"VSS1748"
$PN"R54"4;
"VSS1749"
$PN"T49"4;
"VSS1750"
$PN"T55"4;
"VSS1751"
$PN"R56"4;
"VSS1752"
$PN"R62"4;
"VSS1753"
$PN"R68"4;
"VSS1754"
$PN"R72"4;
"VSS1755"
$PN"R74"4;
"VSS1756"
$PN"R78"4;
"VSS1757"
$PN"R84"4;
"VSS1758"
$PN"R88"4;
"VSS1759"
$PN"R9"4;
"VSS1760"
$PN"T24"4;
"VSS1761"
$PN"T30"4;
"VSS1762"
$PN"T4"4;
"VSS1763"
$PN"T42"4;
"VSS1764"
$PN"T61"4;
"VSS1765"
$PN"T67"4;
"VSS1766"
$PN"U52"4;
"VSS1767"
$PN"T73"4;
"VSS1768"
$PN"T79"4;
"VSS1769"
$PN"T8"4;
"VSS1770"
$PN"T83"4;
"VSS1771"
$PN"U39"4;
"VSS1772"
$PN"U82"4;
"VSS1773"
$PN"U84"4;
"VSS1774"
$PN"U88"4;
"VSS1775"
$PN"V12"5;
"VSS1776"
$PN"V16"5;
"VSS1777"
$PN"V18"5;
"VSS1778"
$PN"V20"5;
"VSS1779"
$PN"V22"5;
"VSS1780"
$PN"V24"5;
"VSS1781"
$PN"V26"5;
"VSS1782"
$PN"V28"5;
"VSS1783"
$PN"V30"5;
"VSS1784"
$PN"V32"5;
"VSS1785"
$PN"V34"5;
"VSS1786"
$PN"V36"5;
"VSS1787"
$PN"V38"5;
"VSS1788"
$PN"V4"5;
"VSS1789"
$PN"V49"5;
"VSS1790"
$PN"V40"5;
"VSS1791"
$PN"V42"5;
"VSS1792"
$PN"V44"5;
"VSS1793"
$PN"V47"5;
"VSS1794"
$PN"V51"5;
"VSS1795"
$PN"V53"5;
"VSS1796"
$PN"V55"5;
"VSS1797"
$PN"V57"5;
"VSS1798"
$PN"V59"5;
"VSS1799"
$PN"V61"5;
"VSS1800"
$PN"V71"5;
"VSS1801"
$PN"V73"5;
"VSS1802"
$PN"V63"5;
"VSS1803"
$PN"V65"5;
"VSS1804"
$PN"V67"5;
"VSS1805"
$PN"V69"5;
"VSS1806"
$PN"V75"5;
"VSS1807"
$PN"V91"5;
"VSS1808"
$PN"W1"5;
"VSS1809"
$PN"W13"5;
"VSS1810"
$PN"V77"5;
"VSS1811"
$PN"V79"5;
"VSS1812"
$PN"V8"5;
"VSS1813"
$PN"V87"5;
"VSS1814"
$PN"W5"5;
"VSS1815"
$PN"W52"5;
"VSS1816"
$PN"W39"5;
"VSS1817"
$PN"W84"5;
"VSS1818"
$PN"W88"5;
"VSS1819"
$PN"W9"5;
"VSS1820"
$PN"Y12"5;
"VSS1821"
$PN"Y16"5;
"VSS1822"
$PN"Y18"5;
"VSS1823"
$PN"Y24"5;
"VSS1824"
$PN"Y30"5;
"VSS1825"
$PN"Y36"5;
"VSS1826"
$PN"Y4"5;
"VSS1827"
$PN"Y42"5;
"VSS1828"
$PN"Y61"5;
"VSS1829"
$PN"Y67"5;
"VSS1830"
$PN"Y49"5;
"VSS1831"
$PN"Y55"5;
"VSS1832"
$PN"Y8"5;
"VSS1833"
$PN"Y73"5;
%"SOCKET4677_AZIF0045P001C01CS"
"41","(1225,1675)","0","pure_quanta","I11";
;
PART_NUMBER"DGA^7000023"
PART_TYPE"SMLF"
MATERIAL"IO"
VALUE"SOCKET4677_AZIF0045-P001C01CS"
$LOCATION"U2"
CDS_LIB"pure_quanta"
NEEDS_NO_SIZE"TRUE"
CDS_LMAN_SYM_OUTLINE"-1050,2150,1050,-2100"
CDS_LOCATION"U2"
$SEC"41"
CDS_SEC"41";
"VSS1126"
$PN"E52"2;
"VSS1129"
$PN"E74"2;
"VSS1131"
$PN"E78"2;
"VSS1272"
$PN"E76"2;
"VSS1273"
$PN"E86"2;
"VSS1494"
$PN"F12"2;
"VSS1495"
$PN"F18"2;
"VSS1502"
$PN"F42"2;
"VSS1504"
$PN"F55"2;
"VSS1507"
$PN"F6"2;
"VSS1508"
$PN"F61"2;
"VSS1509"
$PN"F67"2;
"VSS1510"
$PN"F73"2;
"VSS1511"
$PN"F79"2;
"VSS1514"
$PN"G11"2;
"VSS1516"
$PN"G17"2;
"VSS1519"
$PN"G25"2;
"VSS1521"
$PN"G3"2;
"VSS1523"
$PN"G35"2;
"VSS1527"
$PN"G48"2;
"VSS1532"
$PN"G60"2;
"VSS1534"
$PN"G66"2;
"VSS1535"
$PN"G68"2;
"VSS1536"
$PN"G7"2;
"VSS1538"
$PN"G74"2;
"VSS1544"
$PN"H14"2;
"VSS1546"
$PN"H2"2;
"VSS1558"
$PN"H51"2;
"VSS1560"
$PN"H57"2;
"VSS1564"
$PN"H65"2;
"VSS1567"
$PN"H75"2;
"VSS1570"
$PN"F24"2;
"VSS1571"
$PN"F30"2;
"VSS1572"
$PN"F36"2;
"VSS1573"
$PN"F4"2;
"VSS1574"
$PN"F49"2;
"VSS1575"
$PN"J21"3;
"VSS1576"
$PN"F83"2;
"VSS1577"
$PN"F89"2;
"VSS1578"
$PN"G13"2;
"VSS1579"
$PN"G19"2;
"VSS1580"
$PN"J39"3;
"VSS1581"
$PN"G23"2;
"VSS1582"
$PN"J5"3;
"VSS1583"
$PN"G29"2;
"VSS1584"
$PN"G31"2;
"VSS1585"
$PN"G37"2;
"VSS1586"
$PN"G41"2;
"VSS1587"
$PN"J64"3;
"VSS1588"
$PN"G43"2;
"VSS1589"
$PN"J70"3;
"VSS1590"
$PN"G50"2;
"VSS1591"
$PN"G54"2;
"VSS1592"
$PN"G56"2;
"VSS1593"
$PN"G62"2;
"VSS1594"
$PN"G72"2;
"VSS1595"
$PN"J88"3;
"VSS1596"
$PN"J9"3;
"VSS1597"
$PN"K12"3;
"VSS1598"
$PN"K14"3;
"VSS1599"
$PN"K2"3;
"VSS1600"
$PN"G84"2;
"VSS1601"
$PN"G88"2;
"VSS1602"
$PN"K42"3;
"VSS1603"
$PN"K49"3;
"VSS1604"
$PN"G90"2;
"VSS1605"
$PN"H10"2;
"VSS1606"
$PN"H16"2;
"VSS1607"
$PN"H20"2;
"VSS1608"
$PN"H22"2;
"VSS1609"
$PN"H26"2;
"VSS1610"
$PN"H28"2;
"VSS1611"
$PN"H32"2;
"VSS1612"
$PN"H34"2;
"VSS1613"
$PN"H38"2;
"VSS1614"
$PN"L19"3;
"VSS1615"
$PN"H4"2;
"VSS1616"
$PN"H40"2;
"VSS1617"
$PN"H44"2;
"VSS1618"
$PN"H47"2;
"VSS1619"
$PN"H53"2;
"VSS1620"
$PN"H59"2;
"VSS1621"
$PN"H6"2;
"VSS1622"
$PN"H63"2;
"VSS1623"
$PN"H69"2;
"VSS1624"
$PN"H71"2;
"VSS1625"
$PN"H79"2;
"VSS1626"
$PN"H8"2;
"VSS1627"
$PN"H81"2;
"VSS1628"
$PN"J15"3;
"VSS1629"
$PN"J27"3;
"VSS1630"
$PN"J33"3;
"VSS1631"
$PN"J45"3;
"VSS1632"
$PN"J52"3;
"VSS1633"
$PN"J58"3;
"VSS1634"
$PN"L58"3;
"VSS1635"
$PN"J76"3;
"VSS1636"
$PN"J78"3;
"VSS1637"
$PN"J84"3;
"VSS1638"
$PN"J86"3;
"VSS1639"
$PN"K77"3;
"VSS1640"
$PN"L70"3;
"VSS1641"
$PN"K8"3;
"VSS1642"
$PN"K83"3;
"VSS1643"
$PN"K85"3;
"VSS1644"
$PN"L13"3;
"VSS1645"
$PN"L15"3;
"VSS1646"
$PN"L88"3;
"VSS1647"
$PN"L9"3;
"VSS1648"
$PN"L90"3;
"VSS1649"
$PN"M12"3;
"VSS1650"
$PN"L17"3;
"VSS1651"
$PN"L21"3;
"VSS1652"
$PN"M4"3;
"VSS1653"
$PN"M42"3;
"VSS1654"
$PN"M49"3;
"VSS1655"
$PN"L23"3;
"VSS1656"
$PN"L25"3;
"VSS1657"
$PN"M8"3;
"VSS1658"
$PN"L27"3;
"VSS1659"
$PN"L29"3;
"VSS1660"
$PN"L31"3;
"VSS1661"
$PN"L33"3;
"VSS1662"
$PN"L35"3;
"VSS1663"
$PN"L37"3;
"VSS1664"
$PN"N21"3;
"VSS1665"
$PN"L39"3;
"VSS1666"
$PN"L41"3;
"VSS1667"
$PN"L43"3;
"VSS1668"
$PN"L45"3;
"VSS1669"
$PN"N39"3;
"VSS1670"
$PN"L48"3;
"VSS1671"
$PN"L5"3;
"VSS1672"
$PN"L50"3;
"VSS1673"
$PN"L52"3;
"VSS1674"
$PN"L54"3;
"VSS1675"
$PN"N64"3;
"VSS1676"
$PN"L56"3;
"VSS1677"
$PN"L60"3;
"VSS1678"
$PN"L62"3;
"VSS1679"
$PN"L64"3;
"VSS1680"
$PN"L66"3;
"VSS1681"
$PN"L68"3;
"VSS1682"
$PN"L72"3;
"VSS1683"
$PN"L74"3;
"VSS1684"
$PN"L76"3;
"VSS1685"
$PN"L78"3;
"VSS1686"
$PN"M81"3;
"VSS1687"
$PN"M83"3;
"VSS1688"
$PN"N15"3;
"VSS1689"
$PN"N27"3;
"VSS1691"
$PN"N33"3;
"VSS1692"
$PN"N45"3;
"VSS1693"
$PN"N52"3;
"VSS1694"
$PN"N58"3;
"VSS1695"
$PN"N70"3;
%"SOCKET4677_AZIF0045P001C01CS"
"42","(4250,1725)","0","pure_quanta","I12";
;
PART_NUMBER"DGA^7000023"
PART_TYPE"SMLF"
MATERIAL"IO"
VALUE"SOCKET4677_AZIF0045-P001C01CS"
$LOCATION"U2"
CDS_LIB"pure_quanta"
NEEDS_NO_SIZE"TRUE"
CDS_LMAN_SYM_OUTLINE"-1050,2100,1050,-2050"
CDS_LOCATION"U2"
$SEC"42"
CDS_SEC"42";
"VSS1"
$PN"A11"1;
"VSS2"
$PN"A13"1;
"VSS3"
$PN"A17"1;
"VSS4"
$PN"A19"1;
"VSS5"
$PN"A23"1;
"VSS6"
$PN"A25"1;
"VSS7"
$PN"A29"1;
"VSS8"
$PN"A31"1;
"VSS9"
$PN"A35"1;
"VSS10"
$PN"A37"1;
"VSS11"
$PN"A41"1;
"VSS12"
$PN"A50"1;
"VSS13"
$PN"A54"1;
"VSS14"
$PN"A56"1;
"VSS15"
$PN"A60"1;
"VSS16"
$PN"A62"1;
"VSS378"
$PN"B12"1;
"VSS379"
$PN"B18"1;
"VSS380"
$PN"B24"1;
"VSS381"
$PN"B30"1;
"VSS382"
$PN"B36"1;
"VSS384"
$PN"B42"1;
"VSS385"
$PN"B49"1;
"VSS386"
$PN"B55"1;
"VSS387"
$PN"B6"1;
"VSS388"
$PN"B61"1;
"VSS389"
$PN"B67"1;
"VSS390"
$PN"B75"1;
"VSS391"
$PN"B83"1;
"VSS392"
$PN"B87"1;
"VSS609"
$PN"C39"1;
"VSS610"
$PN"C45"1;
"VSS612"
$PN"C5"1;
"VSS613"
$PN"C52"1;
"VSS614"
$PN"C72"1;
"VSS615"
$PN"C74"1;
"VSS616"
$PN"C78"1;
"VSS617"
$PN"C80"1;
"VSS618"
$PN"C82"1;
"VSS619"
$PN"C86"1;
"VSS657"
$PN"D63"1;
"VSS658"
$PN"D65"1;
"VSS659"
$PN"D67"1;
"VSS662"
$PN"D79"1;
"VSS663"
$PN"D8"1;
"VSS864"
$PN"D10"1;
"VSS865"
$PN"D12"1;
"VSS866"
$PN"D14"1;
"VSS868"
$PN"D16"1;
"VSS869"
$PN"D18"1;
"VSS871"
$PN"D20"1;
"VSS873"
$PN"D22"1;
"VSS874"
$PN"D24"1;
"VSS875"
$PN"D26"1;
"VSS876"
$PN"D28"1;
"VSS877"
$PN"D30"1;
"VSS878"
$PN"D32"1;
"VSS879"
$PN"D34"1;
"VSS881"
$PN"D36"1;
"VSS884"
$PN"D38"1;
"VSS885"
$PN"D40"1;
"VSS886"
$PN"D42"1;
"VSS888"
$PN"D44"1;
"VSS889"
$PN"D47"1;
"VSS891"
$PN"D49"1;
"VSS892"
$PN"D51"1;
"VSS895"
$PN"D53"1;
"VSS896"
$PN"D55"1;
"VSS897"
$PN"D57"1;
"VSS898"
$PN"D59"1;
"VSS899"
$PN"D6"1;
"VSS900"
$PN"D61"1;
"VSS901"
$PN"D69"1;
"VSS902"
$PN"D71"1;
"VSS906"
$PN"D81"1;
"VSS907"
$PN"D83"1;
"VSS1125"
$PN"E5"1;
"VSS1271"
$PN"E39"1;
%"UNIVERSAL_GND"
"1","(-375,-850)","0","logical_power","I3";
;
CDS_LIB"logical_power"
HDL_POWER"GND";
"A"4;
%"UNIVERSAL_GND"
"1","(-225,-850)","0","logical_power","I4";
;
CDS_LIB"logical_power"
HDL_POWER"GND";
"A"3;
%"UNIVERSAL_GND"
"1","(2675,-850)","0","logical_power","I6";
;
CDS_LIB"logical_power"
HDL_POWER"GND";
"A"2;
%"UNIVERSAL_GND"
"1","(2800,-850)","0","logical_power","I7";
;
CDS_LIB"logical_power"
HDL_POWER"GND";
"A"1;
END.
